(kicad_pcb
	(version 20260206)
	(generator "pcbnew")
	(generator_version "10.0")
	(general
		(thickness 1.6)
		(legacy_teardrops no)
	)
	(paper "A4")
	(title_block
		(title "03242023_DA0F0TMBIJ0_F0T_Motherboard_J_brd_V01_OCP.brd")
		(comment 1 "Grand Teton / footprint 1508 of 6105 (J20), pads 113-224 of 291")
	)
	(layers
		(0 "F.Cu" signal "TOP")
		(4 "In1.Cu" signal "GND")
		(6 "In2.Cu" signal "IN1")
		(8 "In3.Cu" signal "GND1")
		(10 "In4.Cu" signal "IN2")
		(12 "In5.Cu" signal "GND2")
		(14 "In6.Cu" signal "IN3")
		(16 "In7.Cu" signal "GND3")
		(18 "In8.Cu" signal "VCC")
		(20 "In9.Cu" signal "VCC1")
		(22 "In10.Cu" signal "GND4")
		(24 "In11.Cu" signal "IN4")
		(26 "In12.Cu" signal "GND5")
		(28 "In13.Cu" signal "IN5")
		(30 "In14.Cu" signal "GND6")
		(32 "In15.Cu" signal "IN6")
		(34 "In16.Cu" signal "GND7")
		(2 "B.Cu" signal "BOTTOM")
		(9 "F.Adhes" user "F.Adhesive")
		(11 "B.Adhes" user "B.Adhesive")
		(13 "F.Paste" user "Package Geometry/Pastemask Top")
		(15 "B.Paste" user "Package Geometry/Pastemask Bottom")
		(5 "F.SilkS" user "Ref Des/Silkscreen Top")
		(7 "B.SilkS" user "Ref Des/Silkscreen Bottom")
		(1 "F.Mask" user "Board Geometry/Soldermask Top")
		(3 "B.Mask" user "Board Geometry/Soldermask Bottom")
		(17 "Dwgs.User" user "User.Drawings")
		(19 "Cmts.User" user "User.Comments")
		(21 "Eco1.User" user "User.Eco1")
		(23 "Eco2.User" user "User.Eco2")
		(25 "Edge.Cuts" user "Board Geometry/Outline")
		(27 "Margin" user)
		(31 "F.CrtYd" user "Package Geometry/Place Bound Top")
		(29 "B.CrtYd" user "Package Geometry/Place Bound Bottom")
		(35 "F.Fab" user "Ref Des/Assembly Top")
		(33 "B.Fab" user "Ref Des/Assembly Bottom")
	)
	(footprint ""
		(layer "F.Cu")
		(at 47.90948 -258.091686)
		(property "Reference" "J20"
			(at -2.74066 -81.678272 0)
			(unlocked yes)
			(layer "F.SilkS")
			(effects
				(font
					(size 0.7874 0.5842)
					(thickness 0.1524)
				)
				(justify left)
			)
		)
		(property "Value" ""
			(at 0 0 0)
			(layer "F.Fab")
			(effects
				(font
					(size 1.27 1.27)
				)
			)
		)
		(duplicate_pad_numbers_are_jumpers no)
		(pad "113" smd rect
			(at -2.050034 36.975034 270)
			(size 0.519938 1.4986)
			(layers "F.Cu" "F.Mask" "F.Paste")
			(net "M_B_CPU1_SB_DQ<9>")
		)
		(pad "114" smd rect
			(at -2.050034 37.824918 270)
			(size 0.519938 1.4986)
			(layers "F.Cu" "F.Mask" "F.Paste")
			(net "GND")
		)
		(pad "115" smd rect
			(at -2.050034 38.675056 270)
			(size 0.519938 1.4986)
			(layers "F.Cu" "F.Mask" "F.Paste")
			(net "M_B_CPU1_SB_DQS_DP<1>")
		)
		(pad "116" smd rect
			(at -2.050034 39.52494 270)
			(size 0.519938 1.4986)
			(layers "F.Cu" "F.Mask" "F.Paste")
			(net "M_B_CPU1_SB_DQS_DN<1>")
		)
		(pad "117" smd rect
			(at -2.050034 40.375078 270)
			(size 0.519938 1.4986)
			(layers "F.Cu" "F.Mask" "F.Paste")
			(net "GND")
		)
		(pad "118" smd rect
			(at -2.050034 41.224962 270)
			(size 0.519938 1.4986)
			(layers "F.Cu" "F.Mask" "F.Paste")
			(net "M_B_CPU1_SB_DQ<12>")
		)
		(pad "119" smd rect
			(at -2.050034 42.0751 270)
			(size 0.519938 1.4986)
			(layers "F.Cu" "F.Mask" "F.Paste")
			(net "GND")
		)
		(pad "120" smd rect
			(at -2.050034 42.924984 270)
			(size 0.519938 1.4986)
			(layers "F.Cu" "F.Mask" "F.Paste")
			(net "M_B_CPU1_SB_DQ<13>")
		)
		(pad "121" smd rect
			(at -2.050034 43.775122 270)
			(size 0.519938 1.4986)
			(layers "F.Cu" "F.Mask" "F.Paste")
			(net "GND")
		)
		(pad "122" smd rect
			(at -2.050034 44.625006 270)
			(size 0.519938 1.4986)
			(layers "F.Cu" "F.Mask" "F.Paste")
			(net "M_B_CPU1_SB_DQ<16>")
		)
		(pad "123" smd rect
			(at -2.050034 45.47489 270)
			(size 0.519938 1.4986)
			(layers "F.Cu" "F.Mask" "F.Paste")
			(net "GND")
		)
		(pad "124" smd rect
			(at -2.050034 46.325028 270)
			(size 0.519938 1.4986)
			(layers "F.Cu" "F.Mask" "F.Paste")
			(net "M_B_CPU1_SB_DQ<17>")
		)
		(pad "125" smd rect
			(at -2.050034 47.174912 270)
			(size 0.519938 1.4986)
			(layers "F.Cu" "F.Mask" "F.Paste")
			(net "GND")
		)
		(pad "126" smd rect
			(at -2.050034 48.02505 270)
			(size 0.519938 1.4986)
			(layers "F.Cu" "F.Mask" "F.Paste")
			(net "M_B_CPU1_SB_DQS_DP<2>")
		)
		(pad "127" smd rect
			(at -2.050034 48.874934 270)
			(size 0.519938 1.4986)
			(layers "F.Cu" "F.Mask" "F.Paste")
			(net "M_B_CPU1_SB_DQS_DN<2>")
		)
		(pad "128" smd rect
			(at -2.050034 49.725072 270)
			(size 0.519938 1.4986)
			(layers "F.Cu" "F.Mask" "F.Paste")
			(net "GND")
		)
		(pad "129" smd rect
			(at -2.050034 50.574956 270)
			(size 0.519938 1.4986)
			(layers "F.Cu" "F.Mask" "F.Paste")
			(net "M_B_CPU1_SB_DQ<20>")
		)
		(pad "130" smd rect
			(at -2.050034 51.425094 270)
			(size 0.519938 1.4986)
			(layers "F.Cu" "F.Mask" "F.Paste")
			(net "GND")
		)
		(pad "131" smd rect
			(at -2.050034 52.274978 270)
			(size 0.519938 1.4986)
			(layers "F.Cu" "F.Mask" "F.Paste")
			(net "M_B_CPU1_SB_DQ<21>")
		)
		(pad "132" smd rect
			(at -2.050034 53.125116 270)
			(size 0.519938 1.4986)
			(layers "F.Cu" "F.Mask" "F.Paste")
			(net "GND")
		)
		(pad "133" smd rect
			(at -2.050034 53.975 270)
			(size 0.519938 1.4986)
			(layers "F.Cu" "F.Mask" "F.Paste")
			(net "M_B_CPU1_SB_DQ<24>")
		)
		(pad "134" smd rect
			(at -2.050034 54.824884 270)
			(size 0.519938 1.4986)
			(layers "F.Cu" "F.Mask" "F.Paste")
			(net "GND")
		)
		(pad "135" smd rect
			(at -2.050034 55.675022 270)
			(size 0.519938 1.4986)
			(layers "F.Cu" "F.Mask" "F.Paste")
			(net "M_B_CPU1_SB_DQ<25>")
		)
		(pad "136" smd rect
			(at -2.050034 56.524906 270)
			(size 0.519938 1.4986)
			(layers "F.Cu" "F.Mask" "F.Paste")
			(net "GND")
		)
		(pad "137" smd rect
			(at -2.050034 57.375044 270)
			(size 0.519938 1.4986)
			(layers "F.Cu" "F.Mask" "F.Paste")
			(net "M_B_CPU1_SB_DQS_DP<3>")
		)
		(pad "138" smd rect
			(at -2.050034 58.224928 270)
			(size 0.519938 1.4986)
			(layers "F.Cu" "F.Mask" "F.Paste")
			(net "M_B_CPU1_SB_DQS_DN<3>")
		)
		(pad "139" smd rect
			(at -2.050034 59.075066 270)
			(size 0.519938 1.4986)
			(layers "F.Cu" "F.Mask" "F.Paste")
			(net "GND")
		)
		(pad "140" smd rect
			(at -2.050034 59.92495 270)
			(size 0.519938 1.4986)
			(layers "F.Cu" "F.Mask" "F.Paste")
			(net "M_B_CPU1_SB_DQ<28>")
		)
		(pad "141" smd rect
			(at -2.050034 60.775088 270)
			(size 0.519938 1.4986)
			(layers "F.Cu" "F.Mask" "F.Paste")
			(net "GND")
		)
		(pad "142" smd rect
			(at -2.050034 61.624972 270)
			(size 0.519938 1.4986)
			(layers "F.Cu" "F.Mask" "F.Paste")
			(net "M_B_CPU1_SB_DQ<29>")
		)
		(pad "143" smd rect
			(at -2.050034 62.47511 270)
			(size 0.519938 1.4986)
			(layers "F.Cu" "F.Mask" "F.Paste")
			(net "GND")
		)
		(pad "144" smd rect
			(at -2.050034 63.324994 270)
			(size 0.519938 1.4986)
			(layers "F.Cu" "F.Mask" "F.Paste")
			(net "TP_CHB_CPU1_DIMM2_FRU_1")
		)
		(pad "145" smd rect
			(at 2.050034 -63.324994 270)
			(size 0.519938 1.4986)
			(layers "F.Cu" "F.Mask" "F.Paste")
			(net "P12V_S3_AUX_CPU1_NVDIMM")
		)
		(pad "146" smd rect
			(at 2.050034 -62.47511 270)
			(size 0.519938 1.4986)
			(layers "F.Cu" "F.Mask" "F.Paste")
			(net "P12V_S3_AUX_CPU1_NVDIMM")
		)
		(pad "147" smd rect
			(at 2.050034 -61.624972 270)
			(size 0.519938 1.4986)
			(layers "F.Cu" "F.Mask" "F.Paste")
			(net "PWRGD_CHB_CPU1_DIMM2")
		)
		(pad "148" smd rect
			(at 2.050034 -60.775088 270)
			(size 0.519938 1.4986)
			(layers "F.Cu" "F.Mask" "F.Paste")
			(net "PD_CHB_CPU1_DIMM2_SAA")
		)
		(pad "149" smd rect
			(at 2.050034 -59.92495 270)
			(size 0.519938 1.4986)
			(layers "F.Cu" "F.Mask" "F.Paste")
			(net "TP_CHB_CPU1_DIMM2_FRU_2")
		)
		(pad "150" smd rect
			(at 2.050034 -59.075066 270)
			(size 0.519938 1.4986)
			(layers "F.Cu" "F.Mask" "F.Paste")
			(net "TP_CHB_CPU1_DIMM2_FRU_3")
		)
		(pad "151" smd rect
			(at 2.050034 -58.224928 270)
			(size 0.519938 1.4986)
			(layers "F.Cu" "F.Mask" "F.Paste")
			(net "GND")
		)
		(pad "152" smd rect
			(at 2.050034 -57.375044 270)
			(size 0.519938 1.4986)
			(layers "F.Cu" "F.Mask" "F.Paste")
			(net "M_B_CPU1_SA_DQ<2>")
		)
		(pad "153" smd rect
			(at 2.050034 -56.524906 270)
			(size 0.519938 1.4986)
			(layers "F.Cu" "F.Mask" "F.Paste")
			(net "GND")
		)
		(pad "154" smd rect
			(at 2.050034 -55.675022 270)
			(size 0.519938 1.4986)
			(layers "F.Cu" "F.Mask" "F.Paste")
			(net "M_B_CPU1_SA_DQ<3>")
		)
		(pad "155" smd rect
			(at 2.050034 -54.824884 270)
			(size 0.519938 1.4986)
			(layers "F.Cu" "F.Mask" "F.Paste")
			(net "GND")
		)
		(pad "156" smd rect
			(at 2.050034 -53.975 270)
			(size 0.519938 1.4986)
			(layers "F.Cu" "F.Mask" "F.Paste")
			(net "M_B_CPU1_SA_DQS_DN<5>")
		)
		(pad "157" smd rect
			(at 2.050034 -53.125116 270)
			(size 0.519938 1.4986)
			(layers "F.Cu" "F.Mask" "F.Paste")
			(net "M_B_CPU1_SA_DQS_DP<5>")
		)
		(pad "158" smd rect
			(at 2.050034 -52.274978 270)
			(size 0.519938 1.4986)
			(layers "F.Cu" "F.Mask" "F.Paste")
			(net "GND")
		)
		(pad "159" smd rect
			(at 2.050034 -51.425094 270)
			(size 0.519938 1.4986)
			(layers "F.Cu" "F.Mask" "F.Paste")
			(net "M_B_CPU1_SA_DQ<6>")
		)
		(pad "160" smd rect
			(at 2.050034 -50.574956 270)
			(size 0.519938 1.4986)
			(layers "F.Cu" "F.Mask" "F.Paste")
			(net "GND")
		)
		(pad "161" smd rect
			(at 2.050034 -49.725072 270)
			(size 0.519938 1.4986)
			(layers "F.Cu" "F.Mask" "F.Paste")
			(net "M_B_CPU1_SA_DQ<7>")
		)
		(pad "162" smd rect
			(at 2.050034 -48.874934 270)
			(size 0.519938 1.4986)
			(layers "F.Cu" "F.Mask" "F.Paste")
			(net "GND")
		)
		(pad "163" smd rect
			(at 2.050034 -48.02505 270)
			(size 0.519938 1.4986)
			(layers "F.Cu" "F.Mask" "F.Paste")
			(net "M_B_CPU1_SA_DQ<10>")
		)
		(pad "164" smd rect
			(at 2.050034 -47.174912 270)
			(size 0.519938 1.4986)
			(layers "F.Cu" "F.Mask" "F.Paste")
			(net "GND")
		)
		(pad "165" smd rect
			(at 2.050034 -46.325028 270)
			(size 0.519938 1.4986)
			(layers "F.Cu" "F.Mask" "F.Paste")
			(net "M_B_CPU1_SA_DQ<11>")
		)
		(pad "166" smd rect
			(at 2.050034 -45.47489 270)
			(size 0.519938 1.4986)
			(layers "F.Cu" "F.Mask" "F.Paste")
			(net "GND")
		)
		(pad "167" smd rect
			(at 2.050034 -44.625006 270)
			(size 0.519938 1.4986)
			(layers "F.Cu" "F.Mask" "F.Paste")
			(net "M_B_CPU1_SA_DQS_DN<6>")
		)
		(pad "168" smd rect
			(at 2.050034 -43.775122 270)
			(size 0.519938 1.4986)
			(layers "F.Cu" "F.Mask" "F.Paste")
			(net "M_B_CPU1_SA_DQS_DP<6>")
		)
		(pad "169" smd rect
			(at 2.050034 -42.924984 270)
			(size 0.519938 1.4986)
			(layers "F.Cu" "F.Mask" "F.Paste")
			(net "GND")
		)
		(pad "170" smd rect
			(at 2.050034 -42.0751 270)
			(size 0.519938 1.4986)
			(layers "F.Cu" "F.Mask" "F.Paste")
			(net "M_B_CPU1_SA_DQ<14>")
		)
		(pad "171" smd rect
			(at 2.050034 -41.224962 270)
			(size 0.519938 1.4986)
			(layers "F.Cu" "F.Mask" "F.Paste")
			(net "GND")
		)
		(pad "172" smd rect
			(at 2.050034 -40.375078 270)
			(size 0.519938 1.4986)
			(layers "F.Cu" "F.Mask" "F.Paste")
			(net "M_B_CPU1_SA_DQ<15>")
		)
		(pad "173" smd rect
			(at 2.050034 -39.52494 270)
			(size 0.519938 1.4986)
			(layers "F.Cu" "F.Mask" "F.Paste")
			(net "GND")
		)
		(pad "174" smd rect
			(at 2.050034 -38.675056 270)
			(size 0.519938 1.4986)
			(layers "F.Cu" "F.Mask" "F.Paste")
			(net "M_B_CPU1_SA_DQ<18>")
		)
		(pad "175" smd rect
			(at 2.050034 -37.824918 270)
			(size 0.519938 1.4986)
			(layers "F.Cu" "F.Mask" "F.Paste")
			(net "GND")
		)
		(pad "176" smd rect
			(at 2.050034 -36.975034 270)
			(size 0.519938 1.4986)
			(layers "F.Cu" "F.Mask" "F.Paste")
			(net "M_B_CPU1_SA_DQ<19>")
		)
		(pad "177" smd rect
			(at 2.050034 -36.124896 270)
			(size 0.519938 1.4986)
			(layers "F.Cu" "F.Mask" "F.Paste")
			(net "GND")
		)
		(pad "178" smd rect
			(at 2.050034 -35.275012 270)
			(size 0.519938 1.4986)
			(layers "F.Cu" "F.Mask" "F.Paste")
			(net "M_B_CPU1_SA_DQS_DN<7>")
		)
		(pad "179" smd rect
			(at 2.050034 -34.425128 270)
			(size 0.519938 1.4986)
			(layers "F.Cu" "F.Mask" "F.Paste")
			(net "M_B_CPU1_SA_DQS_DP<7>")
		)
		(pad "180" smd rect
			(at 2.050034 -33.57499 270)
			(size 0.519938 1.4986)
			(layers "F.Cu" "F.Mask" "F.Paste")
			(net "GND")
		)
		(pad "181" smd rect
			(at 2.050034 -32.725106 270)
			(size 0.519938 1.4986)
			(layers "F.Cu" "F.Mask" "F.Paste")
			(net "M_B_CPU1_SA_DQ<22>")
		)
		(pad "182" smd rect
			(at 2.050034 -31.874968 270)
			(size 0.519938 1.4986)
			(layers "F.Cu" "F.Mask" "F.Paste")
			(net "GND")
		)
		(pad "183" smd rect
			(at 2.050034 -31.025084 270)
			(size 0.519938 1.4986)
			(layers "F.Cu" "F.Mask" "F.Paste")
			(net "M_B_CPU1_SA_DQ<23>")
		)
		(pad "184" smd rect
			(at 2.050034 -30.174946 270)
			(size 0.519938 1.4986)
			(layers "F.Cu" "F.Mask" "F.Paste")
			(net "GND")
		)
		(pad "185" smd rect
			(at 2.050034 -29.325062 270)
			(size 0.519938 1.4986)
			(layers "F.Cu" "F.Mask" "F.Paste")
			(net "M_B_CPU1_SA_DQ<26>")
		)
		(pad "186" smd rect
			(at 2.050034 -28.474924 270)
			(size 0.519938 1.4986)
			(layers "F.Cu" "F.Mask" "F.Paste")
			(net "GND")
		)
		(pad "187" smd rect
			(at 2.050034 -27.62504 270)
			(size 0.519938 1.4986)
			(layers "F.Cu" "F.Mask" "F.Paste")
			(net "M_B_CPU1_SA_DQ<27>")
		)
		(pad "188" smd rect
			(at 2.050034 -26.774902 270)
			(size 0.519938 1.4986)
			(layers "F.Cu" "F.Mask" "F.Paste")
			(net "GND")
		)
		(pad "189" smd rect
			(at 2.050034 -25.925018 270)
			(size 0.519938 1.4986)
			(layers "F.Cu" "F.Mask" "F.Paste")
			(net "M_B_CPU1_SA_DQS_DN<8>")
		)
		(pad "190" smd rect
			(at 2.050034 -25.07488 270)
			(size 0.519938 1.4986)
			(layers "F.Cu" "F.Mask" "F.Paste")
			(net "M_B_CPU1_SA_DQS_DP<8>")
		)
		(pad "191" smd rect
			(at 2.050034 -24.224996 270)
			(size 0.519938 1.4986)
			(layers "F.Cu" "F.Mask" "F.Paste")
			(net "GND")
		)
		(pad "192" smd rect
			(at 2.050034 -23.375112 270)
			(size 0.519938 1.4986)
			(layers "F.Cu" "F.Mask" "F.Paste")
			(net "M_B_CPU1_SA_DQ<30>")
		)
		(pad "193" smd rect
			(at 2.050034 -22.524974 270)
			(size 0.519938 1.4986)
			(layers "F.Cu" "F.Mask" "F.Paste")
			(net "GND")
		)
		(pad "194" smd rect
			(at 2.050034 -21.67509 270)
			(size 0.519938 1.4986)
			(layers "F.Cu" "F.Mask" "F.Paste")
			(net "M_B_CPU1_SA_DQ<31>")
		)
		(pad "195" smd rect
			(at 2.050034 -20.824952 270)
			(size 0.519938 1.4986)
			(layers "F.Cu" "F.Mask" "F.Paste")
			(net "GND")
		)
		(pad "196" smd rect
			(at 2.050034 -19.975068 270)
			(size 0.519938 1.4986)
			(layers "F.Cu" "F.Mask" "F.Paste")
			(net "M_B_CPU1_SA_CB<2>")
		)
		(pad "197" smd rect
			(at 2.050034 -19.12493 270)
			(size 0.519938 1.4986)
			(layers "F.Cu" "F.Mask" "F.Paste")
			(net "GND")
		)
		(pad "198" smd rect
			(at 2.050034 -18.275046 270)
			(size 0.519938 1.4986)
			(layers "F.Cu" "F.Mask" "F.Paste")
			(net "M_B_CPU1_SA_CB<3>")
		)
		(pad "199" smd rect
			(at 2.050034 -17.424908 270)
			(size 0.519938 1.4986)
			(layers "F.Cu" "F.Mask" "F.Paste")
			(net "GND")
		)
		(pad "200" smd rect
			(at 2.050034 -16.575024 270)
			(size 0.519938 1.4986)
			(layers "F.Cu" "F.Mask" "F.Paste")
			(net "M_B_CPU1_SA_DQS_DN<9>")
		)
		(pad "201" smd rect
			(at 2.050034 -15.724886 270)
			(size 0.519938 1.4986)
			(layers "F.Cu" "F.Mask" "F.Paste")
			(net "M_B_CPU1_SA_DQS_DP<9>")
		)
		(pad "202" smd rect
			(at 2.050034 -14.875002 270)
			(size 0.519938 1.4986)
			(layers "F.Cu" "F.Mask" "F.Paste")
			(net "GND")
		)
		(pad "203" smd rect
			(at 2.050034 -14.025118 270)
			(size 0.519938 1.4986)
			(layers "F.Cu" "F.Mask" "F.Paste")
			(net "M_B_CPU1_SA_CB<6>")
		)
		(pad "204" smd rect
			(at 2.050034 -13.17498 270)
			(size 0.519938 1.4986)
			(layers "F.Cu" "F.Mask" "F.Paste")
			(net "GND")
		)
		(pad "205" smd rect
			(at 2.050034 -12.325096 270)
			(size 0.519938 1.4986)
			(layers "F.Cu" "F.Mask" "F.Paste")
			(net "M_B_CPU1_SA_CB<7>")
		)
		(pad "206" smd rect
			(at 2.050034 -11.474958 270)
			(size 0.519938 1.4986)
			(layers "F.Cu" "F.Mask" "F.Paste")
			(net "GND")
		)
		(pad "207" smd rect
			(at 2.050034 -10.625074 270)
			(size 0.519938 1.4986)
			(layers "F.Cu" "F.Mask" "F.Paste")
			(net "RST_M_AB_CPU1_FPGA_N")
		)
		(pad "208" smd rect
			(at 2.050034 -9.774936 270)
			(size 0.519938 1.4986)
			(layers "F.Cu" "F.Mask" "F.Paste")
			(net "GND")
		)
		(pad "209" smd rect
			(at 2.050034 -8.925052 270)
			(size 0.519938 1.4986)
			(layers "F.Cu" "F.Mask" "F.Paste")
			(net "M_B_CPU1_SA_CS_N<3>")
		)
		(pad "210" smd rect
			(at 2.050034 -8.074914 270)
			(size 0.519938 1.4986)
			(layers "F.Cu" "F.Mask" "F.Paste")
			(net "GND")
		)
		(pad "211" smd rect
			(at 2.050034 -7.22503 270)
			(size 0.519938 1.4986)
			(layers "F.Cu" "F.Mask" "F.Paste")
			(net "M_B_CPU1_SA_CA<1>")
		)
		(pad "212" smd rect
			(at 2.050034 -6.374892 270)
			(size 0.519938 1.4986)
			(layers "F.Cu" "F.Mask" "F.Paste")
			(net "GND")
		)
		(pad "213" smd rect
			(at 2.050034 -5.525008 270)
			(size 0.519938 1.4986)
			(layers "F.Cu" "F.Mask" "F.Paste")
			(net "M_B_CPU1_SA_CA<3>")
		)
		(pad "214" smd rect
			(at 2.050034 -4.675124 270)
			(size 0.519938 1.4986)
			(layers "F.Cu" "F.Mask" "F.Paste")
			(net "GND")
		)
		(pad "215" smd rect
			(at 2.050034 -3.824986 270)
			(size 0.519938 1.4986)
			(layers "F.Cu" "F.Mask" "F.Paste")
			(net "M_B_CPU1_SA_CA<5>")
		)
		(pad "216" smd rect
			(at 2.050034 -2.975102 270)
			(size 0.519938 1.4986)
			(layers "F.Cu" "F.Mask" "F.Paste")
			(net "GND")
		)
		(pad "217" smd rect
			(at 2.050034 -2.124964 270)
			(size 0.519938 1.4986)
			(layers "F.Cu" "F.Mask" "F.Paste")
			(net "M_B_CPU1_CLK_DP<1>")
		)
		(pad "218" smd rect
			(at 2.050034 -1.27508 270)
			(size 0.519938 1.4986)
			(layers "F.Cu" "F.Mask" "F.Paste")
			(net "M_B_CPU1_CLK_DN<1>")
		)
		(pad "219" smd rect
			(at 2.050034 -0.424942 270)
			(size 0.519938 1.4986)
			(layers "F.Cu" "F.Mask" "F.Paste")
			(net "GND")
		)
		(pad "220" smd rect
			(at 2.050034 5.525008 270)
			(size 0.519938 1.4986)
			(layers "F.Cu" "F.Mask" "F.Paste")
			(net "TP_CHB_CPU1_DIMM2_FRU_4")
		)
		(pad "221" smd rect
			(at 2.050034 6.374892 270)
			(size 0.519938 1.4986)
			(layers "F.Cu" "F.Mask" "F.Paste")
			(net "M_B_CPU1_SB_CA<1>")
		)
		(pad "222" smd rect
			(at 2.050034 7.22503 270)
			(size 0.519938 1.4986)
			(layers "F.Cu" "F.Mask" "F.Paste")
			(net "GND")
		)
		(pad "223" smd rect
			(at 2.050034 8.074914 270)
			(size 0.519938 1.4986)
			(layers "F.Cu" "F.Mask" "F.Paste")
			(net "M_B_CPU1_SB_CA<3>")
		)
		(pad "224" smd rect
			(at 2.050034 8.925052 270)
			(size 0.519938 1.4986)
			(layers "F.Cu" "F.Mask" "F.Paste")
			(net "GND")
		)
	)
)
